# SCM (Grand Teton) — schematic netlist excerpt (pin names and nets, part order shuffled) for the footprints in the layout excerpt that follows; sources: Cadence DE-HDL packaged netlist, KiCad conversion of 12092022_DA0F0TMDCD0_F0T_Management_Board_D_brd_V3_OCP.brd

C87  Q_CAP  0.1UF 25V 10% X7R  pkg 0402  page 16 : A = P1V8_AUX ; B = GND
C135  Q_CAP  0.01UF 50V 10% X7R  pkg C0402  page 17 : A = GND ; B = A_BMC_ADCVREFP1

(kicad_pcb
	(version 20260206)
	(generator "pcbnew")
	(generator_version "10.0")
	(general
		(thickness 1.6)
		(legacy_teardrops no)
	)
	(paper "A4")
	(title_block
		(title "12092022_DA0F0TMDCD0_F0T_Management_Board_D_brd_V3_OCP.brd")
		(comment 1 "Grand Teton / footprints 875-876 of 1440")
	)
	(layers
		(0 "F.Cu" signal "TOP")
		(4 "In1.Cu" signal "GND")
		(6 "In2.Cu" signal "IN1")
		(8 "In3.Cu" signal "GND1")
		(10 "In4.Cu" signal "IN2")
		(12 "In5.Cu" signal "VCC")
		(14 "In6.Cu" signal "VCC1")
		(16 "In7.Cu" signal "IN3")
		(18 "In8.Cu" signal "GND2")
		(20 "In9.Cu" signal "IN4")
		(22 "In10.Cu" signal "GND3")
		(2 "B.Cu" signal "BOTTOM")
		(9 "F.Adhes" user "F.Adhesive")
		(11 "B.Adhes" user "B.Adhesive")
		(13 "F.Paste" user "Package Geometry/Pastemask Top")
		(15 "B.Paste" user "Package Geometry/Pastemask Bottom")
		(5 "F.SilkS" user "Ref Des/Silkscreen Top")
		(7 "B.SilkS" user "Ref Des/Silkscreen Bottom")
		(1 "F.Mask" user "Board Geometry/Soldermask Top")
		(3 "B.Mask" user "Board Geometry/Soldermask Bottom")
		(17 "Dwgs.User" user "User.Drawings")
		(19 "Cmts.User" user "User.Comments")
		(21 "Eco1.User" user "User.Eco1")
		(23 "Eco2.User" user "User.Eco2")
		(25 "Edge.Cuts" user "Board Geometry/Outline")
		(27 "Margin" user)
		(31 "F.CrtYd" user "Package Geometry/Place Bound Top")
		(29 "B.CrtYd" user "Package Geometry/Place Bound Bottom")
		(35 "F.Fab" user "Ref Des/Assembly Top")
		(33 "B.Fab" user "Ref Des/Assembly Bottom")
	)
	(footprint ""
		(layer "B.Cu")
		(at 51.55946 -61.852048 90)
		(property "Reference" "C135"
			(at 0 0 90)
			(layer "B.SilkS")
			(hide yes)
			(effects
				(font
					(size 1.27 1.27)
				)
				(justify mirror)
			)
		)
		(property "Value" ""
			(at 0 0 90)
			(layer "B.Fab")
			(effects
				(font
					(size 1.27 1.27)
				)
				(justify mirror)
			)
		)
		(duplicate_pad_numbers_are_jumpers no)
		(fp_line
			(start 0.7874 -0.4064)
			(end -0.7874 -0.4064)
			(stroke
				(width 0.1524)
				(type default)
			)
			(layer "B.SilkS")
		)
		(fp_line
			(start -0.7874 -0.4064)
			(end -0.7874 0.4064)
			(stroke
				(width 0.1524)
				(type default)
			)
			(layer "B.SilkS")
		)
		(fp_line
			(start 0.7874 0.4064)
			(end 0.7874 -0.4064)
			(stroke
				(width 0.1524)
				(type default)
			)
			(layer "B.SilkS")
		)
		(fp_line
			(start -0.7874 0.4064)
			(end 0.7874 0.4064)
			(stroke
				(width 0.1524)
				(type default)
			)
			(layer "B.SilkS")
		)
		(fp_line
			(start 0.67945 -0.305054)
			(end 0.12065 -0.305054)
			(stroke
				(width 0.1)
				(type default)
			)
			(layer "B.Fab")
		)
		(fp_line
			(start 0.12065 -0.305054)
			(end 0.12065 -0.2794)
			(stroke
				(width 0.1)
				(type default)
			)
			(layer "B.Fab")
		)
		(fp_line
			(start -0.12065 -0.3048)
			(end -0.67945 -0.3048)
			(stroke
				(width 0.1)
				(type default)
			)
			(layer "B.Fab")
		)
		(fp_line
			(start -0.67945 -0.3048)
			(end -0.67945 0.3048)
			(stroke
				(width 0.1)
				(type default)
			)
			(layer "B.Fab")
		)
		(fp_line
			(start 0.12065 -0.2794)
			(end -0.12065 -0.2794)
			(stroke
				(width 0.1)
				(type default)
			)
			(layer "B.Fab")
		)
		(fp_line
			(start -0.12065 -0.2794)
			(end -0.12065 -0.3048)
			(stroke
				(width 0.1)
				(type default)
			)
			(layer "B.Fab")
		)
		(fp_line
			(start 0.12065 0.2794)
			(end 0.12065 0.3048)
			(stroke
				(width 0.1)
				(type default)
			)
			(layer "B.Fab")
		)
		(fp_line
			(start -0.120396 0.2794)
			(end 0.12065 0.2794)
			(stroke
				(width 0.1)
				(type default)
			)
			(layer "B.Fab")
		)
		(fp_line
			(start 0.67945 0.3048)
			(end 0.67945 -0.305054)
			(stroke
				(width 0.1)
				(type default)
			)
			(layer "B.Fab")
		)
		(fp_line
			(start 0.12065 0.3048)
			(end 0.67945 0.3048)
			(stroke
				(width 0.1)
				(type default)
			)
			(layer "B.Fab")
		)
		(fp_line
			(start -0.120396 0.3048)
			(end -0.120396 0.2794)
			(stroke
				(width 0.1)
				(type default)
			)
			(layer "B.Fab")
		)
		(fp_line
			(start -0.67945 0.3048)
			(end -0.120396 0.3048)
			(stroke
				(width 0.1)
				(type default)
			)
			(layer "B.Fab")
		)
		(pad "1" smd circle
			(at 0.40005 0 270)
			(size 0 0)
			(layers "B.Cu" "B.Mask" "B.Paste")
			(net "GND")
		)
		(pad "2" smd circle
			(at -0.40005 0 270)
			(size 0 0)
			(layers "B.Cu" "B.Mask" "B.Paste")
			(net "A_BMC_ADCVREFP1")
		)
	)
	(footprint ""
		(layer "B.Cu")
		(at 62.103 -54.61 -90)
		(property "Reference" "C87"
			(at 0 0 90)
			(layer "B.SilkS")
			(hide yes)
			(effects
				(font
					(size 1.27 1.27)
				)
				(justify mirror)
			)
		)
		(property "Value" ""
			(at 0 0 90)
			(layer "B.Fab")
			(effects
				(font
					(size 1.27 1.27)
				)
				(justify mirror)
			)
		)
		(duplicate_pad_numbers_are_jumpers no)
		(fp_line
			(start -0.7874 0.4064)
			(end 0.7874 0.4064)
			(stroke
				(width 0.1524)
				(type default)
			)
			(layer "B.SilkS")
		)
		(fp_line
			(start 0.7874 0.4064)
			(end 0.7874 -0.4064)
			(stroke
				(width 0.1524)
				(type default)
			)
			(layer "B.SilkS")
		)
		(fp_line
			(start -0.7874 -0.4064)
			(end -0.7874 0.4064)
			(stroke
				(width 0.1524)
				(type default)
			)
			(layer "B.SilkS")
		)
		(fp_line
			(start 0.7874 -0.4064)
			(end -0.7874 -0.4064)
			(stroke
				(width 0.1524)
				(type default)
			)
			(layer "B.SilkS")
		)
		(fp_line
			(start -0.67945 0.3048)
			(end -0.120396 0.3048)
			(stroke
				(width 0.1)
				(type default)
			)
			(layer "B.Fab")
		)
		(fp_line
			(start -0.120396 0.3048)
			(end -0.120396 0.2794)
			(stroke
				(width 0.1)
				(type default)
			)
			(layer "B.Fab")
		)
		(fp_line
			(start 0.12065 0.3048)
			(end 0.67945 0.3048)
			(stroke
				(width 0.1)
				(type default)
			)
			(layer "B.Fab")
		)
		(fp_line
			(start 0.67945 0.3048)
			(end 0.67945 -0.305054)
			(stroke
				(width 0.1)
				(type default)
			)
			(layer "B.Fab")
		)
		(fp_line
			(start -0.120396 0.2794)
			(end 0.12065 0.2794)
			(stroke
				(width 0.1)
				(type default)
			)
			(layer "B.Fab")
		)
		(fp_line
			(start 0.12065 0.2794)
			(end 0.12065 0.3048)
			(stroke
				(width 0.1)
				(type default)
			)
			(layer "B.Fab")
		)
		(fp_line
			(start -0.12065 -0.2794)
			(end -0.12065 -0.3048)
			(stroke
				(width 0.1)
				(type default)
			)
			(layer "B.Fab")
		)
		(fp_line
			(start 0.12065 -0.2794)
			(end -0.12065 -0.2794)
			(stroke
				(width 0.1)
				(type default)
			)
			(layer "B.Fab")
		)
		(fp_line
			(start -0.67945 -0.3048)
			(end -0.67945 0.3048)
			(stroke
				(width 0.1)
				(type default)
			)
			(layer "B.Fab")
		)
		(fp_line
			(start -0.12065 -0.3048)
			(end -0.67945 -0.3048)
			(stroke
				(width 0.1)
				(type default)
			)
			(layer "B.Fab")
		)
		(fp_line
			(start 0.12065 -0.305054)
			(end 0.12065 -0.2794)
			(stroke
				(width 0.1)
				(type default)
			)
			(layer "B.Fab")
		)
		(fp_line
			(start 0.67945 -0.305054)
			(end 0.12065 -0.305054)
			(stroke
				(width 0.1)
				(type default)
			)
			(layer "B.Fab")
		)
		(pad "1" smd circle
			(at 0.40005 0 90)
			(size 0 0)
			(layers "B.Cu" "B.Mask" "B.Paste")
			(net "P1V8_AUX")
		)
		(pad "2" smd circle
			(at -0.40005 0 90)
			(size 0 0)
			(layers "B.Cu" "B.Mask" "B.Paste")
			(net "GND")
		)
	)
)
